(kicad_pcb
	(version 20260206)
	(generator "pcbnew")
	(generator_version "10.0")
	(general
		(thickness 1.6)
		(legacy_teardrops no)
	)
	(paper "A4")
	(title_block
		(title "Wiwynn_Tioga_Pass_MB.brd")
		(comment 1 "Tioga Pass / footprints 3826-3833 of 4770")
	)
	(layers
		(0 "F.Cu" signal "TOP")
		(4 "In1.Cu" signal "L2GND")
		(6 "In2.Cu" signal "L3")
		(8 "In3.Cu" signal "L4GND")
		(10 "In4.Cu" signal "L5")
		(12 "In5.Cu" signal "L6GND")
		(14 "In6.Cu" signal "L7VCC")
		(16 "In7.Cu" signal "L8VCC")
		(18 "In8.Cu" signal "L9GND")
		(20 "In9.Cu" signal "L10")
		(22 "In10.Cu" signal "L11GND")
		(24 "In11.Cu" signal "L12")
		(26 "In12.Cu" signal "L13GND")
		(2 "B.Cu" signal "BOTTOM")
		(9 "F.Adhes" user "F.Adhesive")
		(11 "B.Adhes" user "B.Adhesive")
		(13 "F.Paste" user "Package Geometry/Pastemask Top")
		(15 "B.Paste" user "Package Geometry/Pastemask Bottom")
		(5 "F.SilkS" user "Ref Des/Silkscreen Top")
		(7 "B.SilkS" user "Ref Des/Silkscreen Bottom")
		(1 "F.Mask" user "Board Geometry/Soldermask Top")
		(3 "B.Mask" user "Board Geometry/Soldermask Bottom")
		(17 "Dwgs.User" user "User.Drawings")
		(19 "Cmts.User" user "User.Comments")
		(21 "Eco1.User" user "User.Eco1")
		(23 "Eco2.User" user "User.Eco2")
		(25 "Edge.Cuts" user "Board Geometry/Outline")
		(27 "Margin" user)
		(31 "F.CrtYd" user "Package Geometry/Place Bound Top")
		(29 "B.CrtYd" user "Package Geometry/Place Bound Bottom")
		(35 "F.Fab" user "Ref Des/Assembly Top")
		(33 "B.Fab" user "Ref Des/Assembly Bottom")
	)
	(footprint ""
		(layer "B.Cu")
		(at 476.1738 -45.6438 -90)
		(property "Reference" "C22W34"
			(at 0 0 90)
			(layer "B.SilkS")
			(hide yes)
			(effects
				(font
					(size 1.27 1.27)
				)
				(justify mirror)
			)
		)
		(property "Value" "*"
			(at 0.0762 -6.2357 270)
			(unlocked yes)
			(layer "B.Fab")
			(hide yes)
			(effects
				(font
					(size 1.27 1.016)
					(thickness 0.1524)
				)
				(justify mirror)
			)
		)
		(property "Device Type" "SC22U16V5MX-4-GP_SMD-BCG5-SC22A"
			(at 0.0762 -8.2677 270)
			(unlocked yes)
			(layer "B.Fab")
			(hide yes)
			(effects
				(font
					(size 1.27 1.016)
					(thickness 0.1524)
				)
				(justify mirror)
			)
		)
		(duplicate_pad_numbers_are_jumpers no)
		(fp_line
			(start -0.635 0)
			(end 0.635 0)
			(stroke
				(width 0.508)
				(type default)
			)
			(layer "B.SilkS")
		)
		(fp_rect
			(start 0.9652 1.778)
			(end -0.9652 -1.778)
			(stroke
				(width 0)
				(type default)
			)
			(fill no)
			(layer "B.CrtYd")
		)
		(fp_poly
			(pts
				(xy 0.9652 -1.778) (xy -0.9652 -1.778) (xy -0.9652 1.778) (xy 0.9652 1.778)
			)
			(stroke
				(width 0)
				(type default)
			)
			(fill no)
			(layer "B.Fab")
		)
		(pad "1" smd rect
			(at 0 -0.9652 90)
			(size 1.397 1.143)
			(layers "B.Cu" "B.Mask" "B.Paste")
			(net "P3V3_STBY")
		)
		(pad "2" smd rect
			(at 0 0.9652 90)
			(size 1.397 1.143)
			(layers "B.Cu" "B.Mask" "B.Paste")
			(net "GND")
		)
	)
	(footprint ""
		(layer "B.Cu")
		(at 49.4284 -59.143392 180)
		(property "Reference" "C9R8"
			(at 0 0 0)
			(layer "B.SilkS")
			(hide yes)
			(effects
				(font
					(size 1.27 1.27)
				)
				(justify mirror)
			)
		)
		(property "Value" ""
			(at 0 0 0)
			(layer "B.Fab")
			(effects
				(font
					(size 1.27 1.27)
				)
				(justify mirror)
			)
		)
		(duplicate_pad_numbers_are_jumpers no)
		(fp_poly
			(pts
				(xy 0.4953 -0.2032) (xy -0.4953 -0.2032) (xy -0.4953 1.6002) (xy 0.4953 1.6002)
			)
			(stroke
				(width 0)
				(type default)
			)
			(fill no)
			(layer "B.CrtYd")
		)
		(fp_line
			(start 0.4953 1.6002)
			(end 0.4953 -0.2032)
			(stroke
				(width 0.1)
				(type default)
			)
			(layer "B.Fab")
		)
		(fp_line
			(start 0.4953 -0.2032)
			(end -0.4953 -0.2032)
			(stroke
				(width 0.1)
				(type default)
			)
			(layer "B.Fab")
		)
		(fp_line
			(start -0.4953 1.6002)
			(end 0.4953 1.6002)
			(stroke
				(width 0.1)
				(type default)
			)
			(layer "B.Fab")
		)
		(fp_line
			(start -0.4953 -0.2032)
			(end -0.4953 1.6002)
			(stroke
				(width 0.1)
				(type default)
			)
			(layer "B.Fab")
		)
		(pad "1" smd rect
			(at 0 0)
			(size 0.762 0.889)
			(layers "B.Cu" "B.Mask" "B.Paste")
			(net "PVCCIN_CPU1")
		)
		(pad "2" smd rect
			(at 0 1.397)
			(size 0.762 0.889)
			(layers "B.Cu" "B.Mask" "B.Paste")
			(net "GND")
		)
		(zone
			(layer "B.Cu")
			(hatch none 0.5)
			(connect_pads
				(clearance 0)
			)
			(min_thickness 0.25)
			(keepout
				(tracks not_allowed)
				(vias allowed)
				(pads allowed)
				(copperpour not_allowed)
				(footprints allowed)
			)
			(placement
				(enabled no)
				(sheetname "")
			)
			(fill
				(thermal_gap 0.5)
				(thermal_bridge_width 0.5)
				(island_removal_mode 0)
			)
			(polygon
				(pts
					(xy 49.0474 -59.587892) (xy 49.8094 -59.587892) (xy 49.8094 -60.095892) (xy 49.0474 -60.095892)
				)
			)
		)
	)
	(footprint ""
		(layer "B.Cu")
		(at 440.284362 -32.184848 180)
		(property "Reference" "C1W20"
			(at 0.8382 -0.67818 180)
			(unlocked yes)
			(layer "B.SilkS")
			(effects
				(font
					(size 0.4064 0.254)
					(thickness 0.1524)
				)
				(justify left mirror)
			)
		)
		(property "Value" ""
			(at 0 0 0)
			(layer "B.Fab")
			(effects
				(font
					(size 1.27 1.27)
				)
				(justify mirror)
			)
		)
		(duplicate_pad_numbers_are_jumpers no)
		(fp_poly
			(pts
				(xy -0.3048 -0.1016) (xy -0.3048 0.9906) (xy 0.3048 0.9906) (xy 0.3048 -0.1016)
			)
			(stroke
				(width 0)
				(type default)
			)
			(fill no)
			(layer "B.CrtYd")
		)
		(fp_line
			(start 0.3048 0.9906)
			(end -0.3048 0.9906)
			(stroke
				(width 0.1)
				(type default)
			)
			(layer "B.Fab")
		)
		(fp_line
			(start 0.3048 -0.1016)
			(end 0.3048 0.9906)
			(stroke
				(width 0.1)
				(type default)
			)
			(layer "B.Fab")
		)
		(fp_line
			(start -0.3048 0.9906)
			(end -0.3048 -0.1016)
			(stroke
				(width 0.1)
				(type default)
			)
			(layer "B.Fab")
		)
		(fp_line
			(start -0.3048 -0.1016)
			(end 0.3048 -0.1016)
			(stroke
				(width 0.1)
				(type default)
			)
			(layer "B.Fab")
		)
		(pad "1" smd rect
			(at 0 0)
			(size 0.508 0.508)
			(layers "B.Cu" "B.Mask" "B.Paste")
			(net "BMC_M_CLK")
		)
		(pad "2" smd rect
			(at 0 0.889)
			(size 0.508 0.508)
			(layers "B.Cu" "B.Mask" "B.Paste")
			(net "GND")
		)
		(zone
			(layer "B.Cu")
			(hatch none 0.5)
			(connect_pads
				(clearance 0)
			)
			(min_thickness 0.25)
			(keepout
				(tracks not_allowed)
				(vias allowed)
				(pads allowed)
				(copperpour not_allowed)
				(footprints allowed)
			)
			(placement
				(enabled no)
				(sheetname "")
			)
			(fill
				(thermal_gap 0.5)
				(thermal_bridge_width 0.5)
				(island_removal_mode 0)
			)
			(polygon
				(pts
					(xy 440.030362 -32.819848) (xy 440.538362 -32.819848) (xy 440.538362 -32.438848) (xy 440.030362 -32.438848)
				)
			)
		)
		(zone
			(layer "B.Cu")
			(hatch none 0.5)
			(connect_pads
				(clearance 0)
			)
			(min_thickness 0.25)
			(keepout
				(tracks allowed)
				(vias not_allowed)
				(pads allowed)
				(copperpour not_allowed)
				(footprints allowed)
			)
			(placement
				(enabled no)
				(sheetname "")
			)
			(fill
				(thermal_gap 0.5)
				(thermal_bridge_width 0.5)
				(island_removal_mode 0)
			)
			(polygon
				(pts
					(xy 440.030362 -32.438848) (xy 440.538362 -32.438848) (xy 440.538362 -32.819848) (xy 440.030362 -32.819848)
				)
			)
		)
	)
	(footprint ""
		(layer "B.Cu")
		(at 443.405006 -43.54195 180)
		(property "Reference" "R25W42"
			(at 0 0 0)
			(layer "B.SilkS")
			(hide yes)
			(effects
				(font
					(size 1.27 1.27)
				)
				(justify mirror)
			)
		)
		(property "Value" "*"
			(at -0.064008 -4.108196 180)
			(unlocked yes)
			(layer "B.Fab")
			(hide yes)
			(effects
				(font
					(size 1.27 1.016)
					(thickness 0.1524)
				)
				(justify mirror)
			)
		)
		(property "Device Type" "120R2F-GP_RCL_GP-120R2F-GP,64.A"
			(at -0.064008 -5.632196 180)
			(unlocked yes)
			(layer "B.Fab")
			(hide yes)
			(effects
				(font
					(size 1.27 1.016)
					(thickness 0.1524)
				)
				(justify mirror)
			)
		)
		(duplicate_pad_numbers_are_jumpers no)
		(fp_line
			(start 0.508 -0.9398)
			(end 0.508 0.9398)
			(stroke
				(width 0.1524)
				(type default)
			)
			(layer "B.SilkS")
		)
		(fp_line
			(start -0.508 -0.9398)
			(end 0.508 -0.9398)
			(stroke
				(width 0.1524)
				(type default)
			)
			(layer "B.SilkS")
		)
		(fp_rect
			(start 0.508 0.9398)
			(end -0.508 -0.9398)
			(stroke
				(width 0)
				(type default)
			)
			(fill no)
			(layer "B.CrtYd")
		)
		(fp_rect
			(start 0.508 0.9398)
			(end -0.508 -0.9398)
			(stroke
				(width 0)
				(type default)
			)
			(fill no)
			(layer "B.Fab")
		)
		(pad "1" smd custom
			(at 0 -0.4445)
			(size 0.1397 0.1397)
			(layers "B.Cu" "B.Mask" "B.Paste")
			(net "BMC_M_A4")
			(options
				(clearance outline)
				(anchor circle)
			)
			(primitives
				(gr_poly
					(pts
						(arc
							(start -0.1778 0.2794)
							(mid -0.249642 0.249642)
							(end -0.2794 0.1778)
						)
						(arc
							(start -0.2794 -0.1778)
							(mid -0.249642 -0.249642)
							(end -0.1778 -0.2794)
						)
						(arc
							(start 0.1778 -0.2794)
							(mid 0.249642 -0.249642)
							(end 0.2794 -0.1778)
						)
						(arc
							(start 0.2794 0.1778)
							(mid 0.249642 0.249642)
							(end 0.1778 0.2794)
						)
					)
					(width 0)
					(fill yes)
				)
			)
		)
		(pad "2" smd custom
			(at 0 0.4445)
			(size 0.1397 0.1397)
			(layers "B.Cu" "B.Mask" "B.Paste")
			(net "P1V2_AUX_BMC")
			(options
				(clearance outline)
				(anchor circle)
			)
			(primitives
				(gr_poly
					(pts
						(arc
							(start -0.1778 0.2794)
							(mid -0.249642 0.249642)
							(end -0.2794 0.1778)
						)
						(arc
							(start -0.2794 -0.1778)
							(mid -0.249642 -0.249642)
							(end -0.1778 -0.2794)
						)
						(arc
							(start 0.1778 -0.2794)
							(mid 0.249642 -0.249642)
							(end 0.2794 -0.1778)
						)
						(arc
							(start 0.2794 0.1778)
							(mid 0.249642 0.249642)
							(end 0.1778 0.2794)
						)
					)
					(width 0)
					(fill yes)
				)
			)
		)
	)
	(footprint ""
		(layer "B.Cu")
		(at 348.5134 -150.387304 -90)
		(property "Reference" "C3L13"
			(at 0 0 90)
			(layer "B.SilkS")
			(hide yes)
			(effects
				(font
					(size 1.27 1.27)
				)
				(justify mirror)
			)
		)
		(property "Value" ""
			(at 0 0 90)
			(layer "B.Fab")
			(effects
				(font
					(size 1.27 1.27)
				)
				(justify mirror)
			)
		)
		(duplicate_pad_numbers_are_jumpers no)
		(fp_poly
			(pts
				(xy 0.7239 -0.2159) (xy -0.7239 -0.2159) (xy -0.7239 1.9939) (xy 0.7239 1.9939)
			)
			(stroke
				(width 0)
				(type default)
			)
			(fill no)
			(layer "B.CrtYd")
		)
		(fp_line
			(start -0.7239 1.9939)
			(end -0.7239 -0.2159)
			(stroke
				(width 0.1)
				(type default)
			)
			(layer "B.Fab")
		)
		(fp_line
			(start 0.7239 1.9939)
			(end -0.7239 1.9939)
			(stroke
				(width 0.1)
				(type default)
			)
			(layer "B.Fab")
		)
		(fp_line
			(start -0.7239 -0.2159)
			(end 0.7239 -0.2159)
			(stroke
				(width 0.1)
				(type default)
			)
			(layer "B.Fab")
		)
		(fp_line
			(start 0.7239 -0.2159)
			(end 0.7239 1.9939)
			(stroke
				(width 0.1)
				(type default)
			)
			(layer "B.Fab")
		)
		(pad "1" smd rect
			(at 0 0 90)
			(size 1.27 1.016)
			(layers "B.Cu" "B.Mask" "B.Paste")
			(net "VR_FET_SW_P12V_STBY_PVDDQ_DEF")
		)
		(pad "2" smd rect
			(at 0 1.778 90)
			(size 1.27 1.016)
			(layers "B.Cu" "B.Mask" "B.Paste")
			(net "GND")
		)
		(zone
			(layer "B.Cu")
			(hatch none 0.5)
			(connect_pads
				(clearance 0)
			)
			(min_thickness 0.25)
			(keepout
				(tracks not_allowed)
				(vias allowed)
				(pads allowed)
				(copperpour not_allowed)
				(footprints allowed)
			)
			(placement
				(enabled no)
				(sheetname "")
			)
			(fill
				(thermal_gap 0.5)
				(thermal_bridge_width 0.5)
				(island_removal_mode 0)
			)
			(polygon
				(pts
					(xy 348.0054 -149.752304) (xy 348.0054 -151.022304) (xy 347.2434 -151.022304) (xy 347.2434 -149.752304)
				)
			)
		)
	)
	(footprint ""
		(layer "B.Cu")
		(at 17.9832 -19.6342 -90)
		(property "Reference" "C9T5"
			(at -3.02133 8.255 0)
			(unlocked yes)
			(layer "B.SilkS")
			(effects
				(font
					(size 0.7874 0.5842)
					(thickness 0.1524)
				)
				(justify mirror)
			)
		)
		(property "Value" ""
			(at 0 0 90)
			(layer "B.Fab")
			(effects
				(font
					(size 1.27 1.27)
				)
				(justify mirror)
			)
		)
		(duplicate_pad_numbers_are_jumpers no)
		(fp_line
			(start -2.286 7.366)
			(end -1.600708 7.366)
			(stroke
				(width 0.1524)
				(type default)
			)
			(layer "B.SilkS")
		)
		(fp_line
			(start -2.286 7.366)
			(end -2.286 1.63195)
			(stroke
				(width 0.1524)
				(type default)
			)
			(layer "B.SilkS")
		)
		(fp_line
			(start 2.286 7.366)
			(end 1.60147 7.366)
			(stroke
				(width 0.1524)
				(type default)
			)
			(layer "B.SilkS")
		)
		(fp_line
			(start 2.286 7.366)
			(end 2.286 1.632712)
			(stroke
				(width 0.1524)
				(type default)
			)
			(layer "B.SilkS")
		)
		(fp_line
			(start -2.504948 1.633728)
			(end -1.6002 1.633728)
			(stroke
				(width 0.1524)
				(type default)
			)
			(layer "B.SilkS")
		)
		(fp_line
			(start 2.563114 1.633728)
			(end 1.6002 1.633728)
			(stroke
				(width 0.1524)
				(type default)
			)
			(layer "B.SilkS")
		)
		(fp_line
			(start -2.504948 -1.616456)
			(end -2.504948 1.633728)
			(stroke
				(width 0.1524)
				(type default)
			)
			(layer "B.SilkS")
		)
		(fp_line
			(start -1.6002 -1.616456)
			(end -2.504948 -1.616456)
			(stroke
				(width 0.1524)
				(type default)
			)
			(layer "B.SilkS")
		)
		(fp_line
			(start 1.6002 -1.616456)
			(end 2.563114 -1.616456)
			(stroke
				(width 0.1524)
				(type default)
			)
			(layer "B.SilkS")
		)
		(fp_line
			(start 2.563114 -1.616456)
			(end 2.563114 1.633728)
			(stroke
				(width 0.1524)
				(type default)
			)
			(layer "B.SilkS")
		)
		(fp_rect
			(start 2.286 -0.254)
			(end -2.286 7.366)
			(stroke
				(width 0)
				(type default)
			)
			(fill no)
			(layer "B.CrtYd")
		)
		(fp_line
			(start -2.286 7.366)
			(end 2.286 7.366)
			(stroke
				(width 0.1)
				(type default)
			)
			(layer "B.Fab")
		)
		(fp_line
			(start 2.286 7.366)
			(end 2.286 -0.254)
			(stroke
				(width 0.1)
				(type default)
			)
			(layer "B.Fab")
		)
		(fp_line
			(start -2.286 -0.254)
			(end -2.286 7.366)
			(stroke
				(width 0.1)
				(type default)
			)
			(layer "B.Fab")
		)
		(fp_line
			(start 2.286 -0.254)
			(end -2.286 -0.254)
			(stroke
				(width 0.1)
				(type default)
			)
			(layer "B.Fab")
		)
		(pad "1" smd rect
			(at 0 0 90)
			(size 2.54 3.048)
			(layers "B.Cu" "B.Mask" "B.Paste")
			(net "PVDDQ_GHJ")
		)
		(pad "2" smd rect
			(at 0 7.112 90)
			(size 2.54 3.048)
			(layers "B.Cu" "B.Mask" "B.Paste")
			(net "GND")
		)
	)
	(footprint ""
		(layer "B.Cu")
		(at 404.483062 -1.524508)
		(property "Reference" "C1L119"
			(at 0.8382 -0.67818 0)
			(unlocked yes)
			(layer "B.SilkS")
			(effects
				(font
					(size 0.4064 0.254)
					(thickness 0.1524)
				)
				(justify left mirror)
			)
		)
		(property "Value" ""
			(at 0 0 0)
			(layer "B.Fab")
			(effects
				(font
					(size 1.27 1.27)
				)
				(justify mirror)
			)
		)
		(duplicate_pad_numbers_are_jumpers no)
		(fp_poly
			(pts
				(xy -0.3048 -0.1016) (xy -0.3048 0.9906) (xy 0.3048 0.9906) (xy 0.3048 -0.1016)
			)
			(stroke
				(width 0)
				(type default)
			)
			(fill no)
			(layer "B.CrtYd")
		)
		(fp_line
			(start -0.3048 -0.1016)
			(end 0.3048 -0.1016)
			(stroke
				(width 0.1)
				(type default)
			)
			(layer "B.Fab")
		)
		(fp_line
			(start -0.3048 0.9906)
			(end -0.3048 -0.1016)
			(stroke
				(width 0.1)
				(type default)
			)
			(layer "B.Fab")
		)
		(fp_line
			(start 0.3048 -0.1016)
			(end 0.3048 0.9906)
			(stroke
				(width 0.1)
				(type default)
			)
			(layer "B.Fab")
		)
		(fp_line
			(start 0.3048 0.9906)
			(end -0.3048 0.9906)
			(stroke
				(width 0.1)
				(type default)
			)
			(layer "B.Fab")
		)
		(pad "1" smd rect
			(at 0 0 180)
			(size 0.508 0.508)
			(layers "B.Cu" "B.Mask" "B.Paste")
			(net "P3V3_STBY")
		)
		(pad "2" smd rect
			(at 0 0.889 180)
			(size 0.508 0.508)
			(layers "B.Cu" "B.Mask" "B.Paste")
			(net "GND")
		)
		(zone
			(layer "B.Cu")
			(hatch none 0.5)
			(connect_pads
				(clearance 0)
			)
			(min_thickness 0.25)
			(keepout
				(tracks allowed)
				(vias not_allowed)
				(pads allowed)
				(copperpour not_allowed)
				(footprints allowed)
			)
			(placement
				(enabled no)
				(sheetname "")
			)
			(fill
				(thermal_gap 0.5)
				(thermal_bridge_width 0.5)
				(island_removal_mode 0)
			)
			(polygon
				(pts
					(xy 404.737062 -1.270508) (xy 404.229062 -1.270508) (xy 404.229062 -0.889508) (xy 404.737062 -0.889508)
				)
			)
		)
		(zone
			(layer "B.Cu")
			(hatch none 0.5)
			(connect_pads
				(clearance 0)
			)
			(min_thickness 0.25)
			(keepout
				(tracks not_allowed)
				(vias allowed)
				(pads allowed)
				(copperpour not_allowed)
				(footprints allowed)
			)
			(placement
				(enabled no)
				(sheetname "")
			)
			(fill
				(thermal_gap 0.5)
				(thermal_bridge_width 0.5)
				(island_removal_mode 0)
			)
			(polygon
				(pts
					(xy 404.737062 -0.889508) (xy 404.229062 -0.889508) (xy 404.229062 -1.270508) (xy 404.737062 -1.270508)
				)
			)
		)
	)
	(footprint ""
		(layer "B.Cu")
		(at 111.381032 -135.4074 90)
		(property "Reference" "C7M1"
			(at -1.848866 0.752348 90)
			(unlocked yes)
			(layer "B.SilkS")
			(effects
				(font
					(size 1.27 0.9652)
					(thickness 0.1524)
				)
				(justify mirror)
			)
		)
		(property "Value" ""
			(at 0 0 90)
			(layer "B.Fab")
			(effects
				(font
					(size 1.27 1.27)
				)
				(justify mirror)
			)
		)
		(duplicate_pad_numbers_are_jumpers no)
		(fp_rect
			(start 0.500126 1.598422)
			(end -0.500126 -0.201422)
			(stroke
				(width 0)
				(type default)
			)
			(fill no)
			(layer "B.CrtYd")
		)
		(fp_line
			(start 0.500126 -0.201422)
			(end -0.500126 -0.201422)
			(stroke
				(width 0.1)
				(type default)
			)
			(layer "B.Fab")
		)
		(fp_line
			(start -0.500126 -0.201422)
			(end -0.500126 1.598422)
			(stroke
				(width 0.1)
				(type default)
			)
			(layer "B.Fab")
		)
		(fp_line
			(start 0.500126 1.598422)
			(end 0.500126 -0.201422)
			(stroke
				(width 0.1)
				(type default)
			)
			(layer "B.Fab")
		)
		(fp_line
			(start -0.500126 1.598422)
			(end 0.500126 1.598422)
			(stroke
				(width 0.1)
				(type default)
			)
			(layer "B.Fab")
		)
		(pad "1" smd rect
			(at 0 0)
			(size 0.889 0.9906)
			(layers "B.Cu" "B.Mask" "B.Paste")
			(net "PVDDQ_KLM")
		)
		(pad "2" smd rect
			(at 0 1.397)
			(size 0.889 0.9906)
			(layers "B.Cu" "B.Mask" "B.Paste")
			(net "GND")
		)
		(zone
			(layer "B.Cu")
			(hatch none 0.5)
			(connect_pads
				(clearance 0)
			)
			(min_thickness 0.25)
			(keepout
				(tracks allowed)
				(vias not_allowed)
				(pads allowed)
				(copperpour not_allowed)
				(footprints allowed)
			)
			(placement
				(enabled no)
				(sheetname "")
			)
			(fill
				(thermal_gap 0.5)
				(thermal_bridge_width 0.5)
				(island_removal_mode 0)
			)
			(polygon
				(pts
					(xy 112.333532 -135.9027) (xy 111.825532 -135.9027) (xy 111.825532 -134.9121) (xy 112.333532 -134.9121)
				)
			)
		)
		(zone
			(layer "B.Cu")
			(hatch none 0.5)
			(connect_pads
				(clearance 0)
			)
			(min_thickness 0.25)
			(keepout
				(tracks not_allowed)
				(vias allowed)
				(pads allowed)
				(copperpour not_allowed)
				(footprints allowed)
			)
			(placement
				(enabled no)
				(sheetname "")
			)
			(fill
				(thermal_gap 0.5)
				(thermal_bridge_width 0.5)
				(island_removal_mode 0)
			)
			(polygon
				(pts
					(xy 112.333532 -135.9027) (xy 111.825532 -135.9027) (xy 111.825532 -134.9121) (xy 112.333532 -134.9121)
				)
			)
		)
	)
)
